(kicad_pcb
	(version 20260206)
	(generator "pcbnew")
	(generator_version "10.0")
	(general
		(thickness 1.6)
		(legacy_teardrops no)
	)
	(paper "A4")
	(title_block
		(title "04192023_DAF0TMB3IC0_F0TG_MB_C_brd_V02_OCP.brd")
		(comment 1 "Grand Teton / footprints 8347-8352 of 8354")
	)
	(layers
		(0 "F.Cu" signal "TOP")
		(4 "In1.Cu" signal "GND")
		(6 "In2.Cu" signal "IN1")
		(8 "In3.Cu" signal "GND1")
		(10 "In4.Cu" signal "IN2")
		(12 "In5.Cu" signal "GND2")
		(14 "In6.Cu" signal "IN3")
		(16 "In7.Cu" signal "GND3")
		(18 "In8.Cu" signal "VCC")
		(20 "In9.Cu" signal "VCC1")
		(22 "In10.Cu" signal "GND4")
		(24 "In11.Cu" signal "IN4")
		(26 "In12.Cu" signal "GND5")
		(28 "In13.Cu" signal "IN5")
		(30 "In14.Cu" signal "GND6")
		(32 "In15.Cu" signal "IN6")
		(34 "In16.Cu" signal "GND7")
		(2 "B.Cu" signal "BOTTOM")
		(9 "F.Adhes" user "F.Adhesive")
		(11 "B.Adhes" user "B.Adhesive")
		(13 "F.Paste" user "Package Geometry/Pastemask Top")
		(15 "B.Paste" user "Package Geometry/Pastemask Bottom")
		(5 "F.SilkS" user "Ref Des/Silkscreen Top")
		(7 "B.SilkS" user "Ref Des/Silkscreen Bottom")
		(1 "F.Mask" user "Board Geometry/Soldermask Top")
		(3 "B.Mask" user "Board Geometry/Soldermask Bottom")
		(17 "Dwgs.User" user "User.Drawings")
		(19 "Cmts.User" user "User.Comments")
		(21 "Eco1.User" user "User.Eco1")
		(23 "Eco2.User" user "User.Eco2")
		(25 "Edge.Cuts" user "Board Geometry/Outline")
		(27 "Margin" user)
		(31 "F.CrtYd" user "Package Geometry/Place Bound Top")
		(29 "B.CrtYd" user "Package Geometry/Place Bound Bottom")
		(35 "F.Fab" user "Ref Des/Assembly Top")
		(33 "B.Fab" user "Ref Des/Assembly Bottom")
	)
	(footprint ""
		(layer "B.Cu")
		(at 400.812508 -330.090272)
		(property "Reference" "R457"
			(at 0 0 0)
			(layer "B.SilkS")
			(hide yes)
			(effects
				(font
					(size 1.27 1.27)
				)
				(justify mirror)
			)
		)
		(property "Value" ""
			(at 0 0 0)
			(layer "B.Fab")
			(effects
				(font
					(size 1.27 1.27)
				)
				(justify mirror)
			)
		)
		(duplicate_pad_numbers_are_jumpers no)
		(fp_line
			(start -0.7874 -0.4064)
			(end -0.7874 0.4064)
			(stroke
				(width 0.1524)
				(type default)
			)
			(layer "B.SilkS")
		)
		(fp_line
			(start -0.7874 0.4064)
			(end 0.7874 0.4064)
			(stroke
				(width 0.1524)
				(type default)
			)
			(layer "B.SilkS")
		)
		(fp_line
			(start 0.7874 -0.4064)
			(end -0.7874 -0.4064)
			(stroke
				(width 0.1524)
				(type default)
			)
			(layer "B.SilkS")
		)
		(fp_line
			(start 0.7874 0.4064)
			(end 0.7874 -0.4064)
			(stroke
				(width 0.1524)
				(type default)
			)
			(layer "B.SilkS")
		)
		(fp_line
			(start -0.67945 -0.3048)
			(end -0.67945 0.3048)
			(stroke
				(width 0.1)
				(type default)
			)
			(layer "B.Fab")
		)
		(fp_line
			(start -0.67945 0.3048)
			(end -0.120396 0.3048)
			(stroke
				(width 0.1)
				(type default)
			)
			(layer "B.Fab")
		)
		(fp_line
			(start -0.12065 -0.3048)
			(end -0.67945 -0.3048)
			(stroke
				(width 0.1)
				(type default)
			)
			(layer "B.Fab")
		)
		(fp_line
			(start -0.12065 -0.2794)
			(end -0.12065 -0.3048)
			(stroke
				(width 0.1)
				(type default)
			)
			(layer "B.Fab")
		)
		(fp_line
			(start -0.120396 0.2794)
			(end 0.12065 0.2794)
			(stroke
				(width 0.1)
				(type default)
			)
			(layer "B.Fab")
		)
		(fp_line
			(start -0.120396 0.3048)
			(end -0.120396 0.2794)
			(stroke
				(width 0.1)
				(type default)
			)
			(layer "B.Fab")
		)
		(fp_line
			(start 0.12065 -0.305054)
			(end 0.12065 -0.2794)
			(stroke
				(width 0.1)
				(type default)
			)
			(layer "B.Fab")
		)
		(fp_line
			(start 0.12065 -0.2794)
			(end -0.12065 -0.2794)
			(stroke
				(width 0.1)
				(type default)
			)
			(layer "B.Fab")
		)
		(fp_line
			(start 0.12065 0.2794)
			(end 0.12065 0.3048)
			(stroke
				(width 0.1)
				(type default)
			)
			(layer "B.Fab")
		)
		(fp_line
			(start 0.12065 0.3048)
			(end 0.67945 0.3048)
			(stroke
				(width 0.1)
				(type default)
			)
			(layer "B.Fab")
		)
		(fp_line
			(start 0.67945 -0.305054)
			(end 0.12065 -0.305054)
			(stroke
				(width 0.1)
				(type default)
			)
			(layer "B.Fab")
		)
		(fp_line
			(start 0.67945 0.3048)
			(end 0.67945 -0.305054)
			(stroke
				(width 0.1)
				(type default)
			)
			(layer "B.Fab")
		)
		(pad "1" smd circle
			(at 0.40005 0 180)
			(size 0 0)
			(layers "B.Cu" "B.Mask" "B.Paste")
			(net "PVDD18_S5_P0")
		)
		(pad "2" smd circle
			(at -0.40005 0 180)
			(size 0 0)
			(layers "B.Cu" "B.Mask" "B.Paste")
			(net "RST_ESPI_CPU0_RSTOUT_N")
		)
	)
	(footprint ""
		(layer "B.Cu")
		(at 234.824016 -322.683632 180)
		(property "Reference" "R1229"
			(at 0 0 0)
			(layer "B.SilkS")
			(hide yes)
			(effects
				(font
					(size 1.27 1.27)
				)
				(justify mirror)
			)
		)
		(property "Value" ""
			(at 0 0 0)
			(layer "B.Fab")
			(effects
				(font
					(size 1.27 1.27)
				)
				(justify mirror)
			)
		)
		(duplicate_pad_numbers_are_jumpers no)
		(fp_line
			(start 0.7874 0.4064)
			(end 0.7874 -0.4064)
			(stroke
				(width 0.1524)
				(type default)
			)
			(layer "B.SilkS")
		)
		(fp_line
			(start 0.7874 -0.4064)
			(end -0.7874 -0.4064)
			(stroke
				(width 0.1524)
				(type default)
			)
			(layer "B.SilkS")
		)
		(fp_line
			(start -0.7874 0.4064)
			(end 0.7874 0.4064)
			(stroke
				(width 0.1524)
				(type default)
			)
			(layer "B.SilkS")
		)
		(fp_line
			(start -0.7874 -0.4064)
			(end -0.7874 0.4064)
			(stroke
				(width 0.1524)
				(type default)
			)
			(layer "B.SilkS")
		)
		(fp_line
			(start 0.67945 0.3048)
			(end 0.67945 -0.305054)
			(stroke
				(width 0.1)
				(type default)
			)
			(layer "B.Fab")
		)
		(fp_line
			(start 0.67945 -0.305054)
			(end 0.12065 -0.305054)
			(stroke
				(width 0.1)
				(type default)
			)
			(layer "B.Fab")
		)
		(fp_line
			(start 0.12065 0.3048)
			(end 0.67945 0.3048)
			(stroke
				(width 0.1)
				(type default)
			)
			(layer "B.Fab")
		)
		(fp_line
			(start 0.12065 0.2794)
			(end 0.12065 0.3048)
			(stroke
				(width 0.1)
				(type default)
			)
			(layer "B.Fab")
		)
		(fp_line
			(start 0.12065 -0.2794)
			(end -0.12065 -0.2794)
			(stroke
				(width 0.1)
				(type default)
			)
			(layer "B.Fab")
		)
		(fp_line
			(start 0.12065 -0.305054)
			(end 0.12065 -0.2794)
			(stroke
				(width 0.1)
				(type default)
			)
			(layer "B.Fab")
		)
		(fp_line
			(start -0.120396 0.3048)
			(end -0.120396 0.2794)
			(stroke
				(width 0.1)
				(type default)
			)
			(layer "B.Fab")
		)
		(fp_line
			(start -0.120396 0.2794)
			(end 0.12065 0.2794)
			(stroke
				(width 0.1)
				(type default)
			)
			(layer "B.Fab")
		)
		(fp_line
			(start -0.12065 -0.2794)
			(end -0.12065 -0.3048)
			(stroke
				(width 0.1)
				(type default)
			)
			(layer "B.Fab")
		)
		(fp_line
			(start -0.12065 -0.3048)
			(end -0.67945 -0.3048)
			(stroke
				(width 0.1)
				(type default)
			)
			(layer "B.Fab")
		)
		(fp_line
			(start -0.67945 0.3048)
			(end -0.120396 0.3048)
			(stroke
				(width 0.1)
				(type default)
			)
			(layer "B.Fab")
		)
		(fp_line
			(start -0.67945 -0.3048)
			(end -0.67945 0.3048)
			(stroke
				(width 0.1)
				(type default)
			)
			(layer "B.Fab")
		)
		(pad "1" smd circle
			(at 0.40005 0)
			(size 0 0)
			(layers "B.Cu" "B.Mask" "B.Paste")
			(net "P1V8_AUX_ADC")
		)
		(pad "2" smd circle
			(at -0.40005 0)
			(size 0 0)
			(layers "B.Cu" "B.Mask" "B.Paste")
			(net "GND")
		)
	)
	(footprint ""
		(layer "B.Cu")
		(at 234.825286 -328.085704 180)
		(property "Reference" "R1222"
			(at 0 0 0)
			(layer "B.SilkS")
			(hide yes)
			(effects
				(font
					(size 1.27 1.27)
				)
				(justify mirror)
			)
		)
		(property "Value" ""
			(at 0 0 0)
			(layer "B.Fab")
			(effects
				(font
					(size 1.27 1.27)
				)
				(justify mirror)
			)
		)
		(duplicate_pad_numbers_are_jumpers no)
		(fp_line
			(start 0.7874 0.4064)
			(end 0.7874 -0.4064)
			(stroke
				(width 0.1524)
				(type default)
			)
			(layer "B.SilkS")
		)
		(fp_line
			(start 0.7874 -0.4064)
			(end -0.7874 -0.4064)
			(stroke
				(width 0.1524)
				(type default)
			)
			(layer "B.SilkS")
		)
		(fp_line
			(start -0.7874 0.4064)
			(end 0.7874 0.4064)
			(stroke
				(width 0.1524)
				(type default)
			)
			(layer "B.SilkS")
		)
		(fp_line
			(start -0.7874 -0.4064)
			(end -0.7874 0.4064)
			(stroke
				(width 0.1524)
				(type default)
			)
			(layer "B.SilkS")
		)
		(fp_line
			(start 0.67945 0.3048)
			(end 0.67945 -0.305054)
			(stroke
				(width 0.1)
				(type default)
			)
			(layer "B.Fab")
		)
		(fp_line
			(start 0.67945 -0.305054)
			(end 0.12065 -0.305054)
			(stroke
				(width 0.1)
				(type default)
			)
			(layer "B.Fab")
		)
		(fp_line
			(start 0.12065 0.3048)
			(end 0.67945 0.3048)
			(stroke
				(width 0.1)
				(type default)
			)
			(layer "B.Fab")
		)
		(fp_line
			(start 0.12065 0.2794)
			(end 0.12065 0.3048)
			(stroke
				(width 0.1)
				(type default)
			)
			(layer "B.Fab")
		)
		(fp_line
			(start 0.12065 -0.2794)
			(end -0.12065 -0.2794)
			(stroke
				(width 0.1)
				(type default)
			)
			(layer "B.Fab")
		)
		(fp_line
			(start 0.12065 -0.305054)
			(end 0.12065 -0.2794)
			(stroke
				(width 0.1)
				(type default)
			)
			(layer "B.Fab")
		)
		(fp_line
			(start -0.120396 0.3048)
			(end -0.120396 0.2794)
			(stroke
				(width 0.1)
				(type default)
			)
			(layer "B.Fab")
		)
		(fp_line
			(start -0.120396 0.2794)
			(end 0.12065 0.2794)
			(stroke
				(width 0.1)
				(type default)
			)
			(layer "B.Fab")
		)
		(fp_line
			(start -0.12065 -0.2794)
			(end -0.12065 -0.3048)
			(stroke
				(width 0.1)
				(type default)
			)
			(layer "B.Fab")
		)
		(fp_line
			(start -0.12065 -0.3048)
			(end -0.67945 -0.3048)
			(stroke
				(width 0.1)
				(type default)
			)
			(layer "B.Fab")
		)
		(fp_line
			(start -0.67945 0.3048)
			(end -0.120396 0.3048)
			(stroke
				(width 0.1)
				(type default)
			)
			(layer "B.Fab")
		)
		(fp_line
			(start -0.67945 -0.3048)
			(end -0.67945 0.3048)
			(stroke
				(width 0.1)
				(type default)
			)
			(layer "B.Fab")
		)
		(pad "1" smd circle
			(at 0.40005 0)
			(size 0 0)
			(layers "B.Cu" "B.Mask" "B.Paste")
			(net "PVDD18_S5_P0_ADC")
		)
		(pad "2" smd circle
			(at -0.40005 0)
			(size 0 0)
			(layers "B.Cu" "B.Mask" "B.Paste")
			(net "GND")
		)
	)
	(footprint ""
		(layer "B.Cu")
		(at 315.004958 -201.926952 90)
		(property "Reference" "R27"
			(at 0 0 90)
			(layer "B.SilkS")
			(hide yes)
			(effects
				(font
					(size 1.27 1.27)
				)
				(justify mirror)
			)
		)
		(property "Value" ""
			(at 0 0 90)
			(layer "B.Fab")
			(effects
				(font
					(size 1.27 1.27)
				)
				(justify mirror)
			)
		)
		(duplicate_pad_numbers_are_jumpers no)
		(fp_line
			(start 0.7874 -0.4064)
			(end -0.7874 -0.4064)
			(stroke
				(width 0.1524)
				(type default)
			)
			(layer "B.SilkS")
		)
		(fp_line
			(start -0.7874 -0.4064)
			(end -0.7874 0.4064)
			(stroke
				(width 0.1524)
				(type default)
			)
			(layer "B.SilkS")
		)
		(fp_line
			(start 0.7874 0.4064)
			(end 0.7874 -0.4064)
			(stroke
				(width 0.1524)
				(type default)
			)
			(layer "B.SilkS")
		)
		(fp_line
			(start -0.7874 0.4064)
			(end 0.7874 0.4064)
			(stroke
				(width 0.1524)
				(type default)
			)
			(layer "B.SilkS")
		)
		(fp_line
			(start 0.67945 -0.305054)
			(end 0.12065 -0.305054)
			(stroke
				(width 0.1)
				(type default)
			)
			(layer "B.Fab")
		)
		(fp_line
			(start 0.12065 -0.305054)
			(end 0.12065 -0.2794)
			(stroke
				(width 0.1)
				(type default)
			)
			(layer "B.Fab")
		)
		(fp_line
			(start -0.12065 -0.3048)
			(end -0.67945 -0.3048)
			(stroke
				(width 0.1)
				(type default)
			)
			(layer "B.Fab")
		)
		(fp_line
			(start -0.67945 -0.3048)
			(end -0.67945 0.3048)
			(stroke
				(width 0.1)
				(type default)
			)
			(layer "B.Fab")
		)
		(fp_line
			(start 0.12065 -0.2794)
			(end -0.12065 -0.2794)
			(stroke
				(width 0.1)
				(type default)
			)
			(layer "B.Fab")
		)
		(fp_line
			(start -0.12065 -0.2794)
			(end -0.12065 -0.3048)
			(stroke
				(width 0.1)
				(type default)
			)
			(layer "B.Fab")
		)
		(fp_line
			(start 0.12065 0.2794)
			(end 0.12065 0.3048)
			(stroke
				(width 0.1)
				(type default)
			)
			(layer "B.Fab")
		)
		(fp_line
			(start -0.120396 0.2794)
			(end 0.12065 0.2794)
			(stroke
				(width 0.1)
				(type default)
			)
			(layer "B.Fab")
		)
		(fp_line
			(start 0.67945 0.3048)
			(end 0.67945 -0.305054)
			(stroke
				(width 0.1)
				(type default)
			)
			(layer "B.Fab")
		)
		(fp_line
			(start 0.12065 0.3048)
			(end 0.67945 0.3048)
			(stroke
				(width 0.1)
				(type default)
			)
			(layer "B.Fab")
		)
		(fp_line
			(start -0.120396 0.3048)
			(end -0.120396 0.2794)
			(stroke
				(width 0.1)
				(type default)
			)
			(layer "B.Fab")
		)
		(fp_line
			(start -0.67945 0.3048)
			(end -0.120396 0.3048)
			(stroke
				(width 0.1)
				(type default)
			)
			(layer "B.Fab")
		)
		(pad "1" smd circle
			(at 0.40005 0 270)
			(size 0 0)
			(layers "B.Cu" "B.Mask" "B.Paste")
			(net "SMB_CPU0_2_R_SCL")
		)
		(pad "2" smd circle
			(at -0.40005 0 270)
			(size 0 0)
			(layers "B.Cu" "B.Mask" "B.Paste")
			(net "SMB_CPU0_2_SCL")
		)
	)
	(footprint ""
		(layer "B.Cu")
		(at 115.384834 -271.395952 180)
		(property "Reference" "C2371"
			(at 0 0 0)
			(layer "B.SilkS")
			(hide yes)
			(effects
				(font
					(size 1.27 1.27)
				)
				(justify mirror)
			)
		)
		(property "Value" ""
			(at 0 0 0)
			(layer "B.Fab")
			(effects
				(font
					(size 1.27 1.27)
				)
				(justify mirror)
			)
		)
		(duplicate_pad_numbers_are_jumpers no)
		(fp_line
			(start 0.7874 0.4064)
			(end 0.7874 -0.4064)
			(stroke
				(width 0.1524)
				(type default)
			)
			(layer "B.SilkS")
		)
		(fp_line
			(start 0.7874 -0.4064)
			(end -0.7874 -0.4064)
			(stroke
				(width 0.1524)
				(type default)
			)
			(layer "B.SilkS")
		)
		(fp_line
			(start -0.7874 0.4064)
			(end 0.7874 0.4064)
			(stroke
				(width 0.1524)
				(type default)
			)
			(layer "B.SilkS")
		)
		(fp_line
			(start -0.7874 -0.4064)
			(end -0.7874 0.4064)
			(stroke
				(width 0.1524)
				(type default)
			)
			(layer "B.SilkS")
		)
		(fp_line
			(start 0.67945 0.3048)
			(end 0.67945 -0.305054)
			(stroke
				(width 0.1)
				(type default)
			)
			(layer "B.Fab")
		)
		(fp_line
			(start 0.67945 -0.305054)
			(end 0.12065 -0.305054)
			(stroke
				(width 0.1)
				(type default)
			)
			(layer "B.Fab")
		)
		(fp_line
			(start 0.12065 0.3048)
			(end 0.67945 0.3048)
			(stroke
				(width 0.1)
				(type default)
			)
			(layer "B.Fab")
		)
		(fp_line
			(start 0.12065 0.2794)
			(end 0.12065 0.3048)
			(stroke
				(width 0.1)
				(type default)
			)
			(layer "B.Fab")
		)
		(fp_line
			(start 0.12065 -0.2794)
			(end -0.12065 -0.2794)
			(stroke
				(width 0.1)
				(type default)
			)
			(layer "B.Fab")
		)
		(fp_line
			(start 0.12065 -0.305054)
			(end 0.12065 -0.2794)
			(stroke
				(width 0.1)
				(type default)
			)
			(layer "B.Fab")
		)
		(fp_line
			(start -0.120396 0.3048)
			(end -0.120396 0.2794)
			(stroke
				(width 0.1)
				(type default)
			)
			(layer "B.Fab")
		)
		(fp_line
			(start -0.120396 0.2794)
			(end 0.12065 0.2794)
			(stroke
				(width 0.1)
				(type default)
			)
			(layer "B.Fab")
		)
		(fp_line
			(start -0.12065 -0.2794)
			(end -0.12065 -0.3048)
			(stroke
				(width 0.1)
				(type default)
			)
			(layer "B.Fab")
		)
		(fp_line
			(start -0.12065 -0.3048)
			(end -0.67945 -0.3048)
			(stroke
				(width 0.1)
				(type default)
			)
			(layer "B.Fab")
		)
		(fp_line
			(start -0.67945 0.3048)
			(end -0.120396 0.3048)
			(stroke
				(width 0.1)
				(type default)
			)
			(layer "B.Fab")
		)
		(fp_line
			(start -0.67945 -0.3048)
			(end -0.67945 0.3048)
			(stroke
				(width 0.1)
				(type default)
			)
			(layer "B.Fab")
		)
		(pad "1" smd circle
			(at 0.40005 0)
			(size 0 0)
			(layers "B.Cu" "B.Mask" "B.Paste")
			(net "PVDDCR_CPU1_P1")
		)
		(pad "2" smd circle
			(at -0.40005 0)
			(size 0 0)
			(layers "B.Cu" "B.Mask" "B.Paste")
			(net "GND")
		)
	)
	(footprint ""
		(layer "B.Cu")
		(at 388.88162 -189.46495 90)
		(property "Reference" "PC496"
			(at 6.321044 0.761746 270)
			(unlocked yes)
			(layer "B.SilkS")
			(effects
				(font
					(size 0.7874 0.5842)
					(thickness 0.1524)
				)
				(justify left mirror)
			)
		)
		(property "Value" ""
			(at 0 0 90)
			(layer "B.Fab")
			(effects
				(font
					(size 1.27 1.27)
				)
				(justify mirror)
			)
		)
		(duplicate_pad_numbers_are_jumpers no)
		(fp_line
			(start 4.533392 -2.249932)
			(end -4.533392 -2.249932)
			(stroke
				(width 0.1524)
				(type default)
			)
			(layer "B.SilkS")
		)
		(fp_line
			(start -4.533392 -2.249932)
			(end -4.533392 2.249932)
			(stroke
				(width 0.1524)
				(type default)
			)
			(layer "B.SilkS")
		)
		(fp_line
			(start 4.533392 2.249932)
			(end 4.533392 -2.249932)
			(stroke
				(width 0.1524)
				(type default)
			)
			(layer "B.SilkS")
		)
		(fp_line
			(start -4.533392 2.249932)
			(end 4.533392 2.249932)
			(stroke
				(width 0.1524)
				(type default)
			)
			(layer "B.SilkS")
		)
		(fp_rect
			(start 4.533392 -2.326132)
			(end 5.39242 2.326132)
			(stroke
				(width 0)
				(type default)
			)
			(fill yes)
			(layer "B.SilkS")
		)
		(fp_line
			(start 3.750056 -2.249932)
			(end -3.750056 -2.249932)
			(stroke
				(width 0.1)
				(type default)
			)
			(layer "B.Fab")
		)
		(fp_line
			(start -3.750056 -2.249932)
			(end -3.750056 2.249932)
			(stroke
				(width 0.1)
				(type default)
			)
			(layer "B.Fab")
		)
		(fp_line
			(start 3.750056 2.249932)
			(end 3.750056 -2.249932)
			(stroke
				(width 0.1)
				(type default)
			)
			(layer "B.Fab")
		)
		(fp_line
			(start -3.750056 2.249932)
			(end 3.750056 2.249932)
			(stroke
				(width 0.1)
				(type default)
			)
			(layer "B.Fab")
		)
		(fp_text user "+"
			(at 6.322314 0.786384 0)
			(unlocked yes)
			(layer "B.SilkS")
			(effects
				(font
					(size 1.905 1.4224)
					(thickness 0.1524)
				)
				(justify left mirror)
			)
		)
		(fp_text user "-"
			(at -4.841748 0.861822 90)
			(unlocked yes)
			(layer "B.SilkS")
			(effects
				(font
					(size 1.905 1.4224)
					(thickness 0.1524)
				)
				(justify left mirror)
			)
		)
		(fp_text user "-"
			(at -4.8514 -0.14605 90)
			(unlocked yes)
			(layer "B.Fab")
			(effects
				(font
					(size 1.905 1.4224)
					(thickness 0.1524)
				)
				(justify left mirror)
			)
		)
		(fp_text user "+"
			(at 6.322314 0.786384 0)
			(unlocked yes)
			(layer "B.Fab")
			(effects
				(font
					(size 1.905 1.4224)
					(thickness 0.1524)
				)
				(justify left mirror)
			)
		)
		(pad "1" smd rect
			(at 3.199892 0 270)
			(size 2.413 2.8194)
			(layers "B.Cu" "B.Mask" "B.Paste")
			(net "PVDDCR_CPU0_P0")
		)
		(pad "2" smd rect
			(at -3.199892 0 270)
			(size 2.413 2.8194)
			(layers "B.Cu" "B.Mask" "B.Paste")
			(net "GND")
		)
	)
)
